(kicad_pcb
	(version 20260206)
	(generator "pcbnew")
	(generator_version "10.0")
	(general
		(thickness 1.6)
		(legacy_teardrops no)
	)
	(paper "A4")
	(title_block
		(title "03242023_DA0F0TMBIJ0_F0T_Motherboard_J_brd_V01_OCP.brd")
		(comment 1 "Grand Teton / footprints 1923-1929 of 6105")
	)
	(layers
		(0 "F.Cu" signal "TOP")
		(4 "In1.Cu" signal "GND")
		(6 "In2.Cu" signal "IN1")
		(8 "In3.Cu" signal "GND1")
		(10 "In4.Cu" signal "IN2")
		(12 "In5.Cu" signal "GND2")
		(14 "In6.Cu" signal "IN3")
		(16 "In7.Cu" signal "GND3")
		(18 "In8.Cu" signal "VCC")
		(20 "In9.Cu" signal "VCC1")
		(22 "In10.Cu" signal "GND4")
		(24 "In11.Cu" signal "IN4")
		(26 "In12.Cu" signal "GND5")
		(28 "In13.Cu" signal "IN5")
		(30 "In14.Cu" signal "GND6")
		(32 "In15.Cu" signal "IN6")
		(34 "In16.Cu" signal "GND7")
		(2 "B.Cu" signal "BOTTOM")
		(9 "F.Adhes" user "F.Adhesive")
		(11 "B.Adhes" user "B.Adhesive")
		(13 "F.Paste" user "Package Geometry/Pastemask Top")
		(15 "B.Paste" user "Package Geometry/Pastemask Bottom")
		(5 "F.SilkS" user "Ref Des/Silkscreen Top")
		(7 "B.SilkS" user "Ref Des/Silkscreen Bottom")
		(1 "F.Mask" user "Board Geometry/Soldermask Top")
		(3 "B.Mask" user "Board Geometry/Soldermask Bottom")
		(17 "Dwgs.User" user "User.Drawings")
		(19 "Cmts.User" user "User.Comments")
		(21 "Eco1.User" user "User.Eco1")
		(23 "Eco2.User" user "User.Eco2")
		(25 "Edge.Cuts" user "Board Geometry/Outline")
		(27 "Margin" user)
		(31 "F.CrtYd" user "Package Geometry/Place Bound Top")
		(29 "B.CrtYd" user "Package Geometry/Place Bound Bottom")
		(35 "F.Fab" user "Ref Des/Assembly Top")
		(33 "B.Fab" user "Ref Des/Assembly Bottom")
	)
	(footprint ""
		(layer "F.Cu")
		(at 107.296204 -244.032024 90)
		(property "Reference" "C288"
			(at 0 0 90)
			(layer "F.SilkS")
			(hide yes)
			(effects
				(font
					(size 1.27 1.27)
				)
			)
		)
		(property "Value" ""
			(at 0 0 90)
			(layer "F.Fab")
			(effects
				(font
					(size 1.27 1.27)
				)
			)
		)
		(duplicate_pad_numbers_are_jumpers no)
		(fp_line
			(start 0.7874 -0.4064)
			(end 0.7874 0.4064)
			(stroke
				(width 0.1524)
				(type default)
			)
			(layer "F.SilkS")
		)
		(fp_line
			(start -0.7874 -0.4064)
			(end 0.7874 -0.4064)
			(stroke
				(width 0.1524)
				(type default)
			)
			(layer "F.SilkS")
		)
		(fp_line
			(start 0.7874 0.4064)
			(end -0.7874 0.4064)
			(stroke
				(width 0.1524)
				(type default)
			)
			(layer "F.SilkS")
		)
		(fp_line
			(start -0.7874 0.4064)
			(end -0.7874 -0.4064)
			(stroke
				(width 0.1524)
				(type default)
			)
			(layer "F.SilkS")
		)
		(fp_line
			(start -0.12065 -0.305054)
			(end -0.12065 -0.2794)
			(stroke
				(width 0.1)
				(type default)
			)
			(layer "F.Fab")
		)
		(fp_line
			(start -0.67945 -0.305054)
			(end -0.12065 -0.305054)
			(stroke
				(width 0.1)
				(type default)
			)
			(layer "F.Fab")
		)
		(fp_line
			(start 0.67945 -0.3048)
			(end 0.67945 0.3048)
			(stroke
				(width 0.1)
				(type default)
			)
			(layer "F.Fab")
		)
		(fp_line
			(start 0.12065 -0.3048)
			(end 0.67945 -0.3048)
			(stroke
				(width 0.1)
				(type default)
			)
			(layer "F.Fab")
		)
		(fp_line
			(start 0.12065 -0.2794)
			(end 0.12065 -0.3048)
			(stroke
				(width 0.1)
				(type default)
			)
			(layer "F.Fab")
		)
		(fp_line
			(start -0.12065 -0.2794)
			(end 0.12065 -0.2794)
			(stroke
				(width 0.1)
				(type default)
			)
			(layer "F.Fab")
		)
		(fp_line
			(start 0.120396 0.2794)
			(end -0.12065 0.2794)
			(stroke
				(width 0.1)
				(type default)
			)
			(layer "F.Fab")
		)
		(fp_line
			(start -0.12065 0.2794)
			(end -0.12065 0.3048)
			(stroke
				(width 0.1)
				(type default)
			)
			(layer "F.Fab")
		)
		(fp_line
			(start 0.67945 0.3048)
			(end 0.120396 0.3048)
			(stroke
				(width 0.1)
				(type default)
			)
			(layer "F.Fab")
		)
		(fp_line
			(start 0.120396 0.3048)
			(end 0.120396 0.2794)
			(stroke
				(width 0.1)
				(type default)
			)
			(layer "F.Fab")
		)
		(fp_line
			(start -0.12065 0.3048)
			(end -0.67945 0.3048)
			(stroke
				(width 0.1)
				(type default)
			)
			(layer "F.Fab")
		)
		(fp_line
			(start -0.67945 0.3048)
			(end -0.67945 -0.305054)
			(stroke
				(width 0.1)
				(type default)
			)
			(layer "F.Fab")
		)
		(pad "1" smd circle
			(at -0.40005 0 90)
			(size 0 0)
			(layers "F.Cu" "F.Mask" "F.Paste")
			(net "PVCCIN_CPU1")
		)
		(pad "2" smd circle
			(at 0.40005 0 90)
			(size 0 0)
			(layers "F.Cu" "F.Mask" "F.Paste")
			(net "GND")
		)
	)
	(footprint ""
		(layer "F.Cu")
		(at 75.705462 -39.675562)
		(property "Reference" "C2017"
			(at 0 0 0)
			(layer "F.SilkS")
			(hide yes)
			(effects
				(font
					(size 1.27 1.27)
				)
			)
		)
		(property "Value" ""
			(at 0 0 0)
			(layer "F.Fab")
			(effects
				(font
					(size 1.27 1.27)
				)
			)
		)
		(duplicate_pad_numbers_are_jumpers no)
		(fp_line
			(start -0.7874 -0.4064)
			(end 0.7874 -0.4064)
			(stroke
				(width 0.1524)
				(type default)
			)
			(layer "F.SilkS")
		)
		(fp_line
			(start -0.7874 0.4064)
			(end -0.7874 -0.4064)
			(stroke
				(width 0.1524)
				(type default)
			)
			(layer "F.SilkS")
		)
		(fp_line
			(start 0.7874 -0.4064)
			(end 0.7874 0.4064)
			(stroke
				(width 0.1524)
				(type default)
			)
			(layer "F.SilkS")
		)
		(fp_line
			(start 0.7874 0.4064)
			(end -0.7874 0.4064)
			(stroke
				(width 0.1524)
				(type default)
			)
			(layer "F.SilkS")
		)
		(fp_line
			(start -0.67945 -0.305054)
			(end -0.12065 -0.305054)
			(stroke
				(width 0.1)
				(type default)
			)
			(layer "F.Fab")
		)
		(fp_line
			(start -0.67945 0.3048)
			(end -0.67945 -0.305054)
			(stroke
				(width 0.1)
				(type default)
			)
			(layer "F.Fab")
		)
		(fp_line
			(start -0.12065 -0.305054)
			(end -0.12065 -0.2794)
			(stroke
				(width 0.1)
				(type default)
			)
			(layer "F.Fab")
		)
		(fp_line
			(start -0.12065 -0.2794)
			(end 0.12065 -0.2794)
			(stroke
				(width 0.1)
				(type default)
			)
			(layer "F.Fab")
		)
		(fp_line
			(start -0.12065 0.2794)
			(end -0.12065 0.3048)
			(stroke
				(width 0.1)
				(type default)
			)
			(layer "F.Fab")
		)
		(fp_line
			(start -0.12065 0.3048)
			(end -0.67945 0.3048)
			(stroke
				(width 0.1)
				(type default)
			)
			(layer "F.Fab")
		)
		(fp_line
			(start 0.120396 0.2794)
			(end -0.12065 0.2794)
			(stroke
				(width 0.1)
				(type default)
			)
			(layer "F.Fab")
		)
		(fp_line
			(start 0.120396 0.3048)
			(end 0.120396 0.2794)
			(stroke
				(width 0.1)
				(type default)
			)
			(layer "F.Fab")
		)
		(fp_line
			(start 0.12065 -0.3048)
			(end 0.67945 -0.3048)
			(stroke
				(width 0.1)
				(type default)
			)
			(layer "F.Fab")
		)
		(fp_line
			(start 0.12065 -0.2794)
			(end 0.12065 -0.3048)
			(stroke
				(width 0.1)
				(type default)
			)
			(layer "F.Fab")
		)
		(fp_line
			(start 0.67945 -0.3048)
			(end 0.67945 0.3048)
			(stroke
				(width 0.1)
				(type default)
			)
			(layer "F.Fab")
		)
		(fp_line
			(start 0.67945 0.3048)
			(end 0.120396 0.3048)
			(stroke
				(width 0.1)
				(type default)
			)
			(layer "F.Fab")
		)
		(pad "1" smd circle
			(at -0.40005 0)
			(size 0 0)
			(layers "F.Cu" "F.Mask" "F.Paste")
			(net "P3V3_OCP_V3_2_R")
		)
		(pad "2" smd circle
			(at 0.40005 0)
			(size 0 0)
			(layers "F.Cu" "F.Mask" "F.Paste")
			(net "GND")
		)
	)
	(footprint ""
		(layer "F.Cu")
		(at 403.951186 -61.94806)
		(property "Reference" "R777"
			(at 0 0 0)
			(layer "F.SilkS")
			(hide yes)
			(effects
				(font
					(size 1.27 1.27)
				)
			)
		)
		(property "Value" ""
			(at 0 0 0)
			(layer "F.Fab")
			(effects
				(font
					(size 1.27 1.27)
				)
			)
		)
		(duplicate_pad_numbers_are_jumpers no)
		(fp_line
			(start -0.7874 -0.4064)
			(end 0.7874 -0.4064)
			(stroke
				(width 0.1524)
				(type default)
			)
			(layer "F.SilkS")
		)
		(fp_line
			(start -0.7874 0.4064)
			(end -0.7874 -0.4064)
			(stroke
				(width 0.1524)
				(type default)
			)
			(layer "F.SilkS")
		)
		(fp_line
			(start 0.7874 -0.4064)
			(end 0.7874 0.4064)
			(stroke
				(width 0.1524)
				(type default)
			)
			(layer "F.SilkS")
		)
		(fp_line
			(start 0.7874 0.4064)
			(end -0.7874 0.4064)
			(stroke
				(width 0.1524)
				(type default)
			)
			(layer "F.SilkS")
		)
		(fp_line
			(start -0.67945 -0.305054)
			(end -0.12065 -0.305054)
			(stroke
				(width 0.1)
				(type default)
			)
			(layer "F.Fab")
		)
		(fp_line
			(start -0.67945 0.3048)
			(end -0.67945 -0.305054)
			(stroke
				(width 0.1)
				(type default)
			)
			(layer "F.Fab")
		)
		(fp_line
			(start -0.12065 -0.305054)
			(end -0.12065 -0.2794)
			(stroke
				(width 0.1)
				(type default)
			)
			(layer "F.Fab")
		)
		(fp_line
			(start -0.12065 -0.2794)
			(end 0.12065 -0.2794)
			(stroke
				(width 0.1)
				(type default)
			)
			(layer "F.Fab")
		)
		(fp_line
			(start -0.12065 0.2794)
			(end -0.12065 0.3048)
			(stroke
				(width 0.1)
				(type default)
			)
			(layer "F.Fab")
		)
		(fp_line
			(start -0.12065 0.3048)
			(end -0.67945 0.3048)
			(stroke
				(width 0.1)
				(type default)
			)
			(layer "F.Fab")
		)
		(fp_line
			(start 0.120396 0.2794)
			(end -0.12065 0.2794)
			(stroke
				(width 0.1)
				(type default)
			)
			(layer "F.Fab")
		)
		(fp_line
			(start 0.120396 0.3048)
			(end 0.120396 0.2794)
			(stroke
				(width 0.1)
				(type default)
			)
			(layer "F.Fab")
		)
		(fp_line
			(start 0.12065 -0.3048)
			(end 0.67945 -0.3048)
			(stroke
				(width 0.1)
				(type default)
			)
			(layer "F.Fab")
		)
		(fp_line
			(start 0.12065 -0.2794)
			(end 0.12065 -0.3048)
			(stroke
				(width 0.1)
				(type default)
			)
			(layer "F.Fab")
		)
		(fp_line
			(start 0.67945 -0.3048)
			(end 0.67945 0.3048)
			(stroke
				(width 0.1)
				(type default)
			)
			(layer "F.Fab")
		)
		(fp_line
			(start 0.67945 0.3048)
			(end 0.120396 0.3048)
			(stroke
				(width 0.1)
				(type default)
			)
			(layer "F.Fab")
		)
		(pad "1" smd circle
			(at -0.40005 0)
			(size 0 0)
			(layers "F.Cu" "F.Mask" "F.Paste")
			(net "JTAG_DBP_PREQ_N_R")
		)
		(pad "2" smd circle
			(at 0.40005 0)
			(size 0 0)
			(layers "F.Cu" "F.Mask" "F.Paste")
			(net "JTAG_DBP_PREQ_N")
		)
	)
	(footprint ""
		(layer "F.Cu")
		(at 56.950102 -337.022186 180)
		(property "Reference" "PR561"
			(at 0 0 180)
			(layer "F.SilkS")
			(hide yes)
			(effects
				(font
					(size 1.27 1.27)
				)
			)
		)
		(property "Value" ""
			(at 0 0 180)
			(layer "F.Fab")
			(effects
				(font
					(size 1.27 1.27)
				)
			)
		)
		(duplicate_pad_numbers_are_jumpers no)
		(fp_line
			(start 0.7874 0.4064)
			(end -0.7874 0.4064)
			(stroke
				(width 0.1524)
				(type default)
			)
			(layer "F.SilkS")
		)
		(fp_line
			(start 0.7874 -0.4064)
			(end 0.7874 0.4064)
			(stroke
				(width 0.1524)
				(type default)
			)
			(layer "F.SilkS")
		)
		(fp_line
			(start -0.7874 0.4064)
			(end -0.7874 -0.4064)
			(stroke
				(width 0.1524)
				(type default)
			)
			(layer "F.SilkS")
		)
		(fp_line
			(start -0.7874 -0.4064)
			(end 0.7874 -0.4064)
			(stroke
				(width 0.1524)
				(type default)
			)
			(layer "F.SilkS")
		)
		(fp_line
			(start 0.67945 0.3048)
			(end 0.120396 0.3048)
			(stroke
				(width 0.1)
				(type default)
			)
			(layer "F.Fab")
		)
		(fp_line
			(start 0.67945 -0.3048)
			(end 0.67945 0.3048)
			(stroke
				(width 0.1)
				(type default)
			)
			(layer "F.Fab")
		)
		(fp_line
			(start 0.12065 -0.2794)
			(end 0.12065 -0.3048)
			(stroke
				(width 0.1)
				(type default)
			)
			(layer "F.Fab")
		)
		(fp_line
			(start 0.12065 -0.3048)
			(end 0.67945 -0.3048)
			(stroke
				(width 0.1)
				(type default)
			)
			(layer "F.Fab")
		)
		(fp_line
			(start 0.120396 0.3048)
			(end 0.120396 0.2794)
			(stroke
				(width 0.1)
				(type default)
			)
			(layer "F.Fab")
		)
		(fp_line
			(start 0.120396 0.2794)
			(end -0.12065 0.2794)
			(stroke
				(width 0.1)
				(type default)
			)
			(layer "F.Fab")
		)
		(fp_line
			(start -0.12065 0.3048)
			(end -0.67945 0.3048)
			(stroke
				(width 0.1)
				(type default)
			)
			(layer "F.Fab")
		)
		(fp_line
			(start -0.12065 0.2794)
			(end -0.12065 0.3048)
			(stroke
				(width 0.1)
				(type default)
			)
			(layer "F.Fab")
		)
		(fp_line
			(start -0.12065 -0.2794)
			(end 0.12065 -0.2794)
			(stroke
				(width 0.1)
				(type default)
			)
			(layer "F.Fab")
		)
		(fp_line
			(start -0.12065 -0.305054)
			(end -0.12065 -0.2794)
			(stroke
				(width 0.1)
				(type default)
			)
			(layer "F.Fab")
		)
		(fp_line
			(start -0.67945 0.3048)
			(end -0.67945 -0.305054)
			(stroke
				(width 0.1)
				(type default)
			)
			(layer "F.Fab")
		)
		(fp_line
			(start -0.67945 -0.305054)
			(end -0.12065 -0.305054)
			(stroke
				(width 0.1)
				(type default)
			)
			(layer "F.Fab")
		)
		(pad "1" smd circle
			(at -0.40005 0 180)
			(size 0 0)
			(layers "F.Cu" "F.Mask" "F.Paste")
			(net "VSENSE_PVCCFA_EHV_FIVRA_CPU1_DP")
		)
		(pad "2" smd circle
			(at 0.40005 0 180)
			(size 0 0)
			(layers "F.Cu" "F.Mask" "F.Paste")
			(net "PVCCFA_EHV_FIVRA_CPU1")
		)
	)
	(footprint ""
		(layer "F.Cu")
		(at 228.760782 -127.399542 180)
		(property "Reference" "R563"
			(at 0 0 180)
			(layer "F.SilkS")
			(hide yes)
			(effects
				(font
					(size 1.27 1.27)
				)
			)
		)
		(property "Value" ""
			(at 0 0 180)
			(layer "F.Fab")
			(effects
				(font
					(size 1.27 1.27)
				)
			)
		)
		(duplicate_pad_numbers_are_jumpers no)
		(fp_line
			(start 0.7874 0.4064)
			(end -0.7874 0.4064)
			(stroke
				(width 0.1524)
				(type default)
			)
			(layer "F.SilkS")
		)
		(fp_line
			(start 0.7874 -0.107442)
			(end 0.7874 0.4064)
			(stroke
				(width 0.1524)
				(type default)
			)
			(layer "F.SilkS")
		)
		(fp_line
			(start -0.433578 -0.4064)
			(end 0.330962 -0.4064)
			(stroke
				(width 0.1524)
				(type default)
			)
			(layer "F.SilkS")
		)
		(fp_line
			(start -0.7874 0.4064)
			(end -0.7874 -0.041402)
			(stroke
				(width 0.1524)
				(type default)
			)
			(layer "F.SilkS")
		)
		(fp_line
			(start 0.67945 0.3048)
			(end 0.120396 0.3048)
			(stroke
				(width 0.1)
				(type default)
			)
			(layer "F.Fab")
		)
		(fp_line
			(start 0.67945 -0.3048)
			(end 0.67945 0.3048)
			(stroke
				(width 0.1)
				(type default)
			)
			(layer "F.Fab")
		)
		(fp_line
			(start 0.12065 -0.2794)
			(end 0.12065 -0.3048)
			(stroke
				(width 0.1)
				(type default)
			)
			(layer "F.Fab")
		)
		(fp_line
			(start 0.12065 -0.3048)
			(end 0.67945 -0.3048)
			(stroke
				(width 0.1)
				(type default)
			)
			(layer "F.Fab")
		)
		(fp_line
			(start 0.120396 0.3048)
			(end 0.120396 0.2794)
			(stroke
				(width 0.1)
				(type default)
			)
			(layer "F.Fab")
		)
		(fp_line
			(start 0.120396 0.2794)
			(end -0.12065 0.2794)
			(stroke
				(width 0.1)
				(type default)
			)
			(layer "F.Fab")
		)
		(fp_line
			(start -0.12065 0.3048)
			(end -0.67945 0.3048)
			(stroke
				(width 0.1)
				(type default)
			)
			(layer "F.Fab")
		)
		(fp_line
			(start -0.12065 0.2794)
			(end -0.12065 0.3048)
			(stroke
				(width 0.1)
				(type default)
			)
			(layer "F.Fab")
		)
		(fp_line
			(start -0.12065 -0.2794)
			(end 0.12065 -0.2794)
			(stroke
				(width 0.1)
				(type default)
			)
			(layer "F.Fab")
		)
		(fp_line
			(start -0.12065 -0.305054)
			(end -0.12065 -0.2794)
			(stroke
				(width 0.1)
				(type default)
			)
			(layer "F.Fab")
		)
		(fp_line
			(start -0.67945 0.3048)
			(end -0.67945 -0.305054)
			(stroke
				(width 0.1)
				(type default)
			)
			(layer "F.Fab")
		)
		(fp_line
			(start -0.67945 -0.305054)
			(end -0.12065 -0.305054)
			(stroke
				(width 0.1)
				(type default)
			)
			(layer "F.Fab")
		)
		(pad "1" smd circle
			(at -0.40005 0 180)
			(size 0 0)
			(layers "F.Cu" "F.Mask" "F.Paste")
			(net "CLK_100M_OCP_SFF_0_R_DP")
		)
		(pad "2" smd circle
			(at 0.40005 0 180)
			(size 0 0)
			(layers "F.Cu" "F.Mask" "F.Paste")
			(net "CLK_100M_OCP_SFF_0_DP")
		)
	)
	(footprint ""
		(layer "F.Cu")
		(at 398.16405 -408.517344 -90)
		(property "Reference" "C887"
			(at 0 0 270)
			(layer "F.SilkS")
			(hide yes)
			(effects
				(font
					(size 1.27 1.27)
				)
			)
		)
		(property "Value" ""
			(at 0 0 270)
			(layer "F.Fab")
			(effects
				(font
					(size 1.27 1.27)
				)
			)
		)
		(duplicate_pad_numbers_are_jumpers no)
		(fp_line
			(start -0.299974 0.150114)
			(end -0.299974 -0.150114)
			(stroke
				(width 0.1)
				(type default)
			)
			(layer "F.Fab")
		)
		(fp_line
			(start 0.299974 0.150114)
			(end -0.299974 0.150114)
			(stroke
				(width 0.1)
				(type default)
			)
			(layer "F.Fab")
		)
		(fp_line
			(start -0.299974 -0.150114)
			(end 0.299974 -0.150114)
			(stroke
				(width 0.1)
				(type default)
			)
			(layer "F.Fab")
		)
		(fp_line
			(start 0.299974 -0.150114)
			(end 0.299974 0.150114)
			(stroke
				(width 0.1)
				(type default)
			)
			(layer "F.Fab")
		)
		(pad "1" smd rect
			(at -0.2667 0 270)
			(size 0.3048 0.381)
			(layers "F.Cu" "F.Mask" "F.Paste")
			(net "P5E_CPU0_PE3_TX_C_DP<7>")
		)
		(pad "2" smd rect
			(at 0.2667 0 270)
			(size 0.3048 0.381)
			(layers "F.Cu" "F.Mask" "F.Paste")
			(net "P5E_CPU0_PE3_TX_DP<7>")
		)
	)
	(footprint ""
		(layer "F.Cu")
		(at 147.698714 -402.371052 -90)
		(property "Reference" "C761"
			(at 0 0 270)
			(layer "F.SilkS")
			(hide yes)
			(effects
				(font
					(size 1.27 1.27)
				)
			)
		)
		(property "Value" ""
			(at 0 0 270)
			(layer "F.Fab")
			(effects
				(font
					(size 1.27 1.27)
				)
			)
		)
		(duplicate_pad_numbers_are_jumpers no)
		(fp_line
			(start -0.299974 0.150114)
			(end -0.299974 -0.150114)
			(stroke
				(width 0.1)
				(type default)
			)
			(layer "F.Fab")
		)
		(fp_line
			(start 0.299974 0.150114)
			(end -0.299974 0.150114)
			(stroke
				(width 0.1)
				(type default)
			)
			(layer "F.Fab")
		)
		(fp_line
			(start -0.299974 -0.150114)
			(end 0.299974 -0.150114)
			(stroke
				(width 0.1)
				(type default)
			)
			(layer "F.Fab")
		)
		(fp_line
			(start 0.299974 -0.150114)
			(end 0.299974 0.150114)
			(stroke
				(width 0.1)
				(type default)
			)
			(layer "F.Fab")
		)
		(pad "1" smd rect
			(at -0.2667 0 270)
			(size 0.3048 0.381)
			(layers "F.Cu" "F.Mask" "F.Paste")
			(net "P5E_CPU1_PE2_TX_C_DP<6>")
		)
		(pad "2" smd rect
			(at 0.2667 0 270)
			(size 0.3048 0.381)
			(layers "F.Cu" "F.Mask" "F.Paste")
			(net "P5E_CPU1_PE2_TX_DP<6>")
		)
	)
)
